(kicad_pcb
	(version 20260206)
	(generator "pcbnew")
	(generator_version "10.0")
	(general
		(thickness 1.6)
		(legacy_teardrops no)
	)
	(paper "A4")
	(title_block
		(title "04192023_DAF0TMB3IC0_F0TG_MB_C_brd_V02_OCP.brd")
		(comment 1 "Grand Teton / footprints 5496-5501 of 8354")
	)
	(layers
		(0 "F.Cu" signal "TOP")
		(4 "In1.Cu" signal "GND")
		(6 "In2.Cu" signal "IN1")
		(8 "In3.Cu" signal "GND1")
		(10 "In4.Cu" signal "IN2")
		(12 "In5.Cu" signal "GND2")
		(14 "In6.Cu" signal "IN3")
		(16 "In7.Cu" signal "GND3")
		(18 "In8.Cu" signal "VCC")
		(20 "In9.Cu" signal "VCC1")
		(22 "In10.Cu" signal "GND4")
		(24 "In11.Cu" signal "IN4")
		(26 "In12.Cu" signal "GND5")
		(28 "In13.Cu" signal "IN5")
		(30 "In14.Cu" signal "GND6")
		(32 "In15.Cu" signal "IN6")
		(34 "In16.Cu" signal "GND7")
		(2 "B.Cu" signal "BOTTOM")
		(9 "F.Adhes" user "F.Adhesive")
		(11 "B.Adhes" user "B.Adhesive")
		(13 "F.Paste" user "Package Geometry/Pastemask Top")
		(15 "B.Paste" user "Package Geometry/Pastemask Bottom")
		(5 "F.SilkS" user "Ref Des/Silkscreen Top")
		(7 "B.SilkS" user "Ref Des/Silkscreen Bottom")
		(1 "F.Mask" user "Board Geometry/Soldermask Top")
		(3 "B.Mask" user "Board Geometry/Soldermask Bottom")
		(17 "Dwgs.User" user "User.Drawings")
		(19 "Cmts.User" user "User.Comments")
		(21 "Eco1.User" user "User.Eco1")
		(23 "Eco2.User" user "User.Eco2")
		(25 "Edge.Cuts" user "Board Geometry/Outline")
		(27 "Margin" user)
		(31 "F.CrtYd" user "Package Geometry/Place Bound Top")
		(29 "B.CrtYd" user "Package Geometry/Place Bound Bottom")
		(35 "F.Fab" user "Ref Des/Assembly Top")
		(33 "B.Fab" user "Ref Des/Assembly Bottom")
	)
	(footprint ""
		(layer "B.Cu")
		(at 432.21402 -437.142636 180)
		(property "Reference" "Q137"
			(at -1.600708 -3.202686 0)
			(unlocked yes)
			(layer "B.SilkS")
			(effects
				(font
					(size 0.7874 0.5842)
					(thickness 0.1524)
				)
				(justify left mirror)
			)
		)
		(property "Value" ""
			(at 0 0 0)
			(layer "B.Fab")
			(effects
				(font
					(size 1.27 1.27)
				)
				(justify mirror)
			)
		)
		(duplicate_pad_numbers_are_jumpers no)
		(fp_line
			(start 1.332738 1.100074)
			(end 1.332738 -1.100074)
			(stroke
				(width 0.1524)
				(type default)
			)
			(layer "B.SilkS")
		)
		(fp_line
			(start 1.332738 -1.100074)
			(end 0.4826 -1.100074)
			(stroke
				(width 0.1524)
				(type default)
			)
			(layer "B.SilkS")
		)
		(fp_line
			(start 0.4826 -1.100074)
			(end 0 -0.541274)
			(stroke
				(width 0.1524)
				(type default)
			)
			(layer "B.SilkS")
		)
		(fp_line
			(start 0 -0.541274)
			(end -0.4826 -1.100074)
			(stroke
				(width 0.1524)
				(type default)
			)
			(layer "B.SilkS")
		)
		(fp_line
			(start -0.4826 -1.100074)
			(end -1.332738 -1.100074)
			(stroke
				(width 0.1524)
				(type default)
			)
			(layer "B.SilkS")
		)
		(fp_line
			(start -1.332738 1.100074)
			(end 1.332738 1.100074)
			(stroke
				(width 0.1524)
				(type default)
			)
			(layer "B.SilkS")
		)
		(fp_line
			(start -1.332738 -1.100074)
			(end -1.332738 1.100074)
			(stroke
				(width 0.1524)
				(type default)
			)
			(layer "B.SilkS")
		)
		(fp_poly
			(pts
				(xy 1.255522 -1.262126) (xy 2.00025 -1.510284) (xy 1.50368 -2.006854)
			)
			(stroke
				(width 0)
				(type default)
			)
			(fill yes)
			(layer "B.SilkS")
		)
		(fp_line
			(start 0.674878 1.100074)
			(end 0.674878 -1.100074)
			(stroke
				(width 0.1)
				(type default)
			)
			(layer "B.Fab")
		)
		(fp_line
			(start 0.674878 -1.100074)
			(end -0.674878 -1.100074)
			(stroke
				(width 0.1)
				(type default)
			)
			(layer "B.Fab")
		)
		(fp_line
			(start -0.674878 1.100074)
			(end 0.674878 1.100074)
			(stroke
				(width 0.1)
				(type default)
			)
			(layer "B.Fab")
		)
		(fp_line
			(start -0.674878 -1.100074)
			(end -0.674878 1.100074)
			(stroke
				(width 0.1)
				(type default)
			)
			(layer "B.Fab")
		)
		(fp_poly
			(pts
				(xy 2.2352 -0.298958) (xy 2.2352 -1.001014) (xy 1.533144 -0.649986)
			)
			(stroke
				(width 0)
				(type default)
			)
			(fill yes)
			(layer "B.Fab")
		)
		(pad "1" smd rect
			(at 0.94996 -0.649986 270)
			(size 0.4318 0.508)
			(layers "B.Cu" "B.Mask" "B.Paste")
			(net "GND")
		)
		(pad "2" smd rect
			(at 0.94996 0 270)
			(size 0.4318 0.508)
			(layers "B.Cu" "B.Mask" "B.Paste")
			(net "GPU_3V3IO_RSVD3")
		)
		(pad "3" smd rect
			(at 0.94996 0.649986 270)
			(size 0.4318 0.508)
			(layers "B.Cu" "B.Mask" "B.Paste")
			(net "GPU_3V3IO_RSVD3_ISO")
		)
		(pad "4" smd rect
			(at -0.94996 0.649986 270)
			(size 0.4318 0.508)
			(layers "B.Cu" "B.Mask" "B.Paste")
			(net "GND")
		)
		(pad "5" smd rect
			(at -0.94996 0 270)
			(size 0.4318 0.508)
			(layers "B.Cu" "B.Mask" "B.Paste")
			(net "GPU_3V3IO_RSVD3_N")
		)
		(pad "6" smd rect
			(at -0.94996 -0.649986 270)
			(size 0.4318 0.508)
			(layers "B.Cu" "B.Mask" "B.Paste")
			(net "GPU_3V3IO_RSVD3_N")
		)
	)
	(footprint ""
		(layer "B.Cu")
		(at 351.518728 -398.942052 90)
		(property "Reference" "C656"
			(at 0 0 90)
			(layer "B.SilkS")
			(hide yes)
			(effects
				(font
					(size 1.27 1.27)
				)
				(justify mirror)
			)
		)
		(property "Value" ""
			(at 0 0 90)
			(layer "B.Fab")
			(effects
				(font
					(size 1.27 1.27)
				)
				(justify mirror)
			)
		)
		(duplicate_pad_numbers_are_jumpers no)
		(fp_line
			(start 0.7874 -0.4064)
			(end -0.7874 -0.4064)
			(stroke
				(width 0.1524)
				(type default)
			)
			(layer "B.SilkS")
		)
		(fp_line
			(start -0.7874 -0.4064)
			(end -0.7874 0.4064)
			(stroke
				(width 0.1524)
				(type default)
			)
			(layer "B.SilkS")
		)
		(fp_line
			(start 0.7874 0.4064)
			(end 0.7874 -0.4064)
			(stroke
				(width 0.1524)
				(type default)
			)
			(layer "B.SilkS")
		)
		(fp_line
			(start -0.7874 0.4064)
			(end 0.7874 0.4064)
			(stroke
				(width 0.1524)
				(type default)
			)
			(layer "B.SilkS")
		)
		(fp_line
			(start 0.67945 -0.305054)
			(end 0.12065 -0.305054)
			(stroke
				(width 0.1)
				(type default)
			)
			(layer "B.Fab")
		)
		(fp_line
			(start 0.12065 -0.305054)
			(end 0.12065 -0.2794)
			(stroke
				(width 0.1)
				(type default)
			)
			(layer "B.Fab")
		)
		(fp_line
			(start -0.12065 -0.3048)
			(end -0.67945 -0.3048)
			(stroke
				(width 0.1)
				(type default)
			)
			(layer "B.Fab")
		)
		(fp_line
			(start -0.67945 -0.3048)
			(end -0.67945 0.3048)
			(stroke
				(width 0.1)
				(type default)
			)
			(layer "B.Fab")
		)
		(fp_line
			(start 0.12065 -0.2794)
			(end -0.12065 -0.2794)
			(stroke
				(width 0.1)
				(type default)
			)
			(layer "B.Fab")
		)
		(fp_line
			(start -0.12065 -0.2794)
			(end -0.12065 -0.3048)
			(stroke
				(width 0.1)
				(type default)
			)
			(layer "B.Fab")
		)
		(fp_line
			(start 0.12065 0.2794)
			(end 0.12065 0.3048)
			(stroke
				(width 0.1)
				(type default)
			)
			(layer "B.Fab")
		)
		(fp_line
			(start -0.120396 0.2794)
			(end 0.12065 0.2794)
			(stroke
				(width 0.1)
				(type default)
			)
			(layer "B.Fab")
		)
		(fp_line
			(start 0.67945 0.3048)
			(end 0.67945 -0.305054)
			(stroke
				(width 0.1)
				(type default)
			)
			(layer "B.Fab")
		)
		(fp_line
			(start 0.12065 0.3048)
			(end 0.67945 0.3048)
			(stroke
				(width 0.1)
				(type default)
			)
			(layer "B.Fab")
		)
		(fp_line
			(start -0.120396 0.3048)
			(end -0.120396 0.2794)
			(stroke
				(width 0.1)
				(type default)
			)
			(layer "B.Fab")
		)
		(fp_line
			(start -0.67945 0.3048)
			(end -0.120396 0.3048)
			(stroke
				(width 0.1)
				(type default)
			)
			(layer "B.Fab")
		)
		(pad "1" smd circle
			(at 0.40005 0 270)
			(size 0 0)
			(layers "B.Cu" "B.Mask" "B.Paste")
			(net "P0V9_CPU0_RT1_2A")
		)
		(pad "2" smd circle
			(at -0.40005 0 270)
			(size 0 0)
			(layers "B.Cu" "B.Mask" "B.Paste")
			(net "GND")
		)
	)
	(footprint ""
		(layer "B.Cu")
		(at 171.82846 -190.948564 180)
		(property "Reference" "R310"
			(at 0 0 0)
			(layer "B.SilkS")
			(hide yes)
			(effects
				(font
					(size 1.27 1.27)
				)
				(justify mirror)
			)
		)
		(property "Value" ""
			(at 0 0 0)
			(layer "B.Fab")
			(effects
				(font
					(size 1.27 1.27)
				)
				(justify mirror)
			)
		)
		(duplicate_pad_numbers_are_jumpers no)
		(fp_line
			(start 0.7874 0.4064)
			(end 0.7874 -0.4064)
			(stroke
				(width 0.1524)
				(type default)
			)
			(layer "B.SilkS")
		)
		(fp_line
			(start 0.7874 -0.4064)
			(end -0.7874 -0.4064)
			(stroke
				(width 0.1524)
				(type default)
			)
			(layer "B.SilkS")
		)
		(fp_line
			(start -0.7874 0.4064)
			(end 0.7874 0.4064)
			(stroke
				(width 0.1524)
				(type default)
			)
			(layer "B.SilkS")
		)
		(fp_line
			(start -0.7874 -0.4064)
			(end -0.7874 0.4064)
			(stroke
				(width 0.1524)
				(type default)
			)
			(layer "B.SilkS")
		)
		(fp_line
			(start 0.67945 0.3048)
			(end 0.67945 -0.305054)
			(stroke
				(width 0.1)
				(type default)
			)
			(layer "B.Fab")
		)
		(fp_line
			(start 0.67945 -0.305054)
			(end 0.12065 -0.305054)
			(stroke
				(width 0.1)
				(type default)
			)
			(layer "B.Fab")
		)
		(fp_line
			(start 0.12065 0.3048)
			(end 0.67945 0.3048)
			(stroke
				(width 0.1)
				(type default)
			)
			(layer "B.Fab")
		)
		(fp_line
			(start 0.12065 0.2794)
			(end 0.12065 0.3048)
			(stroke
				(width 0.1)
				(type default)
			)
			(layer "B.Fab")
		)
		(fp_line
			(start 0.12065 -0.2794)
			(end -0.12065 -0.2794)
			(stroke
				(width 0.1)
				(type default)
			)
			(layer "B.Fab")
		)
		(fp_line
			(start 0.12065 -0.305054)
			(end 0.12065 -0.2794)
			(stroke
				(width 0.1)
				(type default)
			)
			(layer "B.Fab")
		)
		(fp_line
			(start -0.120396 0.3048)
			(end -0.120396 0.2794)
			(stroke
				(width 0.1)
				(type default)
			)
			(layer "B.Fab")
		)
		(fp_line
			(start -0.120396 0.2794)
			(end 0.12065 0.2794)
			(stroke
				(width 0.1)
				(type default)
			)
			(layer "B.Fab")
		)
		(fp_line
			(start -0.12065 -0.2794)
			(end -0.12065 -0.3048)
			(stroke
				(width 0.1)
				(type default)
			)
			(layer "B.Fab")
		)
		(fp_line
			(start -0.12065 -0.3048)
			(end -0.67945 -0.3048)
			(stroke
				(width 0.1)
				(type default)
			)
			(layer "B.Fab")
		)
		(fp_line
			(start -0.67945 0.3048)
			(end -0.120396 0.3048)
			(stroke
				(width 0.1)
				(type default)
			)
			(layer "B.Fab")
		)
		(fp_line
			(start -0.67945 -0.3048)
			(end -0.67945 0.3048)
			(stroke
				(width 0.1)
				(type default)
			)
			(layer "B.Fab")
		)
		(pad "1" smd circle
			(at 0.40005 0)
			(size 0 0)
			(layers "B.Cu" "B.Mask" "B.Paste")
			(net "PWRGD_CHH_CPU1_DIMM")
		)
		(pad "2" smd circle
			(at -0.40005 0)
			(size 0 0)
			(layers "B.Cu" "B.Mask" "B.Paste")
			(net "PWRGD_CHGL_CPU1")
		)
	)
	(footprint ""
		(layer "B.Cu")
		(at 105.537 -419.989)
		(property "Reference" "R3032"
			(at 0 0 0)
			(layer "B.SilkS")
			(hide yes)
			(effects
				(font
					(size 1.27 1.27)
				)
				(justify mirror)
			)
		)
		(property "Value" ""
			(at 0 0 0)
			(layer "B.Fab")
			(effects
				(font
					(size 1.27 1.27)
				)
				(justify mirror)
			)
		)
		(duplicate_pad_numbers_are_jumpers no)
		(fp_line
			(start -0.7874 -0.4064)
			(end -0.7874 0.4064)
			(stroke
				(width 0.1524)
				(type default)
			)
			(layer "B.SilkS")
		)
		(fp_line
			(start -0.7874 0.4064)
			(end 0.7874 0.4064)
			(stroke
				(width 0.1524)
				(type default)
			)
			(layer "B.SilkS")
		)
		(fp_line
			(start 0.7874 -0.4064)
			(end -0.7874 -0.4064)
			(stroke
				(width 0.1524)
				(type default)
			)
			(layer "B.SilkS")
		)
		(fp_line
			(start 0.7874 0.4064)
			(end 0.7874 -0.4064)
			(stroke
				(width 0.1524)
				(type default)
			)
			(layer "B.SilkS")
		)
		(fp_line
			(start -0.67945 -0.3048)
			(end -0.67945 0.3048)
			(stroke
				(width 0.1)
				(type default)
			)
			(layer "B.Fab")
		)
		(fp_line
			(start -0.67945 0.3048)
			(end -0.120396 0.3048)
			(stroke
				(width 0.1)
				(type default)
			)
			(layer "B.Fab")
		)
		(fp_line
			(start -0.12065 -0.3048)
			(end -0.67945 -0.3048)
			(stroke
				(width 0.1)
				(type default)
			)
			(layer "B.Fab")
		)
		(fp_line
			(start -0.12065 -0.2794)
			(end -0.12065 -0.3048)
			(stroke
				(width 0.1)
				(type default)
			)
			(layer "B.Fab")
		)
		(fp_line
			(start -0.120396 0.2794)
			(end 0.12065 0.2794)
			(stroke
				(width 0.1)
				(type default)
			)
			(layer "B.Fab")
		)
		(fp_line
			(start -0.120396 0.3048)
			(end -0.120396 0.2794)
			(stroke
				(width 0.1)
				(type default)
			)
			(layer "B.Fab")
		)
		(fp_line
			(start 0.12065 -0.305054)
			(end 0.12065 -0.2794)
			(stroke
				(width 0.1)
				(type default)
			)
			(layer "B.Fab")
		)
		(fp_line
			(start 0.12065 -0.2794)
			(end -0.12065 -0.2794)
			(stroke
				(width 0.1)
				(type default)
			)
			(layer "B.Fab")
		)
		(fp_line
			(start 0.12065 0.2794)
			(end 0.12065 0.3048)
			(stroke
				(width 0.1)
				(type default)
			)
			(layer "B.Fab")
		)
		(fp_line
			(start 0.12065 0.3048)
			(end 0.67945 0.3048)
			(stroke
				(width 0.1)
				(type default)
			)
			(layer "B.Fab")
		)
		(fp_line
			(start 0.67945 -0.305054)
			(end 0.12065 -0.305054)
			(stroke
				(width 0.1)
				(type default)
			)
			(layer "B.Fab")
		)
		(fp_line
			(start 0.67945 0.3048)
			(end 0.67945 -0.305054)
			(stroke
				(width 0.1)
				(type default)
			)
			(layer "B.Fab")
		)
		(pad "1" smd circle
			(at 0.40005 0 180)
			(size 0 0)
			(layers "B.Cu" "B.Mask" "B.Paste")
			(net "FM_SMB_2_ALERT_GPU_N")
		)
		(pad "2" smd circle
			(at -0.40005 0 180)
			(size 0 0)
			(layers "B.Cu" "B.Mask" "B.Paste")
			(net "GND")
		)
	)
	(footprint ""
		(layer "B.Cu")
		(at 104.850946 -343.878916 -90)
		(property "Reference" "PC147_6"
			(at 0 0 90)
			(layer "B.SilkS")
			(hide yes)
			(effects
				(font
					(size 1.27 1.27)
				)
				(justify mirror)
			)
		)
		(property "Value" ""
			(at 0 0 90)
			(layer "B.Fab")
			(effects
				(font
					(size 1.27 1.27)
				)
				(justify mirror)
			)
		)
		(duplicate_pad_numbers_are_jumpers no)
		(fp_line
			(start -1.524 0.762)
			(end 1.524 0.762)
			(stroke
				(width 0.1524)
				(type default)
			)
			(layer "B.SilkS")
		)
		(fp_line
			(start 1.524 0.762)
			(end 1.524 -0.762)
			(stroke
				(width 0.1524)
				(type default)
			)
			(layer "B.SilkS")
		)
		(fp_line
			(start -1.524 -0.762)
			(end -1.524 0.762)
			(stroke
				(width 0.1524)
				(type default)
			)
			(layer "B.SilkS")
		)
		(fp_line
			(start 1.524 -0.762)
			(end -1.524 -0.762)
			(stroke
				(width 0.1524)
				(type default)
			)
			(layer "B.SilkS")
		)
		(fp_line
			(start -1.1049 0.724916)
			(end -1.1049 -0.724916)
			(stroke
				(width 0.1)
				(type default)
			)
			(layer "B.Fab")
		)
		(fp_line
			(start 1.1049 0.724916)
			(end -1.1049 0.724916)
			(stroke
				(width 0.1)
				(type default)
			)
			(layer "B.Fab")
		)
		(fp_line
			(start -1.1049 -0.724916)
			(end 1.1049 -0.724916)
			(stroke
				(width 0.1)
				(type default)
			)
			(layer "B.Fab")
		)
		(fp_line
			(start 1.1049 -0.724916)
			(end 1.1049 0.724916)
			(stroke
				(width 0.1)
				(type default)
			)
			(layer "B.Fab")
		)
		(pad "1" smd rect
			(at 0.889 0 270)
			(size 1.016 1.27)
			(layers "B.Cu" "B.Mask" "B.Paste")
			(net "SW_P12V_AUX_PVDDCR_CPU1_P1_FLT")
		)
		(pad "2" smd rect
			(at -0.889 0 270)
			(size 1.016 1.27)
			(layers "B.Cu" "B.Mask" "B.Paste")
			(net "GND")
		)
	)
	(footprint ""
		(layer "B.Cu")
		(at 235.839 -240.411 -90)
		(property "Reference" "R1157"
			(at 0 0 90)
			(layer "B.SilkS")
			(hide yes)
			(effects
				(font
					(size 1.27 1.27)
				)
				(justify mirror)
			)
		)
		(property "Value" ""
			(at 0 0 90)
			(layer "B.Fab")
			(effects
				(font
					(size 1.27 1.27)
				)
				(justify mirror)
			)
		)
		(duplicate_pad_numbers_are_jumpers no)
		(fp_line
			(start -0.7874 0.4064)
			(end 0.7874 0.4064)
			(stroke
				(width 0.1524)
				(type default)
			)
			(layer "B.SilkS")
		)
		(fp_line
			(start 0.7874 0.4064)
			(end 0.7874 -0.4064)
			(stroke
				(width 0.1524)
				(type default)
			)
			(layer "B.SilkS")
		)
		(fp_line
			(start -0.7874 -0.4064)
			(end -0.7874 0.4064)
			(stroke
				(width 0.1524)
				(type default)
			)
			(layer "B.SilkS")
		)
		(fp_line
			(start 0.7874 -0.4064)
			(end -0.7874 -0.4064)
			(stroke
				(width 0.1524)
				(type default)
			)
			(layer "B.SilkS")
		)
		(fp_line
			(start -0.67945 0.3048)
			(end -0.120396 0.3048)
			(stroke
				(width 0.1)
				(type default)
			)
			(layer "B.Fab")
		)
		(fp_line
			(start -0.120396 0.3048)
			(end -0.120396 0.2794)
			(stroke
				(width 0.1)
				(type default)
			)
			(layer "B.Fab")
		)
		(fp_line
			(start 0.12065 0.3048)
			(end 0.67945 0.3048)
			(stroke
				(width 0.1)
				(type default)
			)
			(layer "B.Fab")
		)
		(fp_line
			(start 0.67945 0.3048)
			(end 0.67945 -0.305054)
			(stroke
				(width 0.1)
				(type default)
			)
			(layer "B.Fab")
		)
		(fp_line
			(start -0.120396 0.2794)
			(end 0.12065 0.2794)
			(stroke
				(width 0.1)
				(type default)
			)
			(layer "B.Fab")
		)
		(fp_line
			(start 0.12065 0.2794)
			(end 0.12065 0.3048)
			(stroke
				(width 0.1)
				(type default)
			)
			(layer "B.Fab")
		)
		(fp_line
			(start -0.12065 -0.2794)
			(end -0.12065 -0.3048)
			(stroke
				(width 0.1)
				(type default)
			)
			(layer "B.Fab")
		)
		(fp_line
			(start 0.12065 -0.2794)
			(end -0.12065 -0.2794)
			(stroke
				(width 0.1)
				(type default)
			)
			(layer "B.Fab")
		)
		(fp_line
			(start -0.67945 -0.3048)
			(end -0.67945 0.3048)
			(stroke
				(width 0.1)
				(type default)
			)
			(layer "B.Fab")
		)
		(fp_line
			(start -0.12065 -0.3048)
			(end -0.67945 -0.3048)
			(stroke
				(width 0.1)
				(type default)
			)
			(layer "B.Fab")
		)
		(fp_line
			(start 0.12065 -0.305054)
			(end 0.12065 -0.2794)
			(stroke
				(width 0.1)
				(type default)
			)
			(layer "B.Fab")
		)
		(fp_line
			(start 0.67945 -0.305054)
			(end 0.12065 -0.305054)
			(stroke
				(width 0.1)
				(type default)
			)
			(layer "B.Fab")
		)
		(pad "1" smd rect
			(at 0.40005 0 270)
			(size 0.4572 0.508)
			(layers "B.Cu" "B.Mask" "B.Paste")
			(net "SMB_APML_CPU1_R_SCL")
		)
		(pad "2" smd rect
			(at -0.40005 0 270)
			(size 0.4572 0.508)
			(layers "B.Cu" "B.Mask" "B.Paste")
			(net "SMB_APML_CPU1_SCL")
		)
	)
)
